FILE_TYPE=LIBRARY_PARTS;
primitive 'SNLABEL_A';
  pin
  end_pin;
  body
    CLASS='MECHANICAL';
    PART_NAME='SNLABEL_A';
    PINCOUNT='0';
    PHYS_DES_PREFIX='LB';
  end_body;
end_primitive;
END.
